(kicad_pcb
	(version 20260206)
	(generator "pcbnew")
	(generator_version "10.0")
	(general
		(thickness 1.6)
		(legacy_teardrops no)
	)
	(paper "A4")
	(title_block
		(title "01162023_DA0F0TEBIF0_F0T_Expander_BD_F_brd_V02_OCP.brd")
		(comment 1 "Grand Teton / footprints 2650-2656 of 9728")
	)
	(layers
		(0 "F.Cu" signal "TOP")
		(4 "In1.Cu" signal "GND")
		(6 "In2.Cu" signal "VCC")
		(8 "In3.Cu" signal "VCC1")
		(10 "In4.Cu" signal "GND1")
		(12 "In5.Cu" signal "IN1")
		(14 "In6.Cu" signal "GND2")
		(16 "In7.Cu" signal "IN2")
		(18 "In8.Cu" signal "GND3")
		(20 "In9.Cu" signal "IN3")
		(22 "In10.Cu" signal "GND4")
		(24 "In11.Cu" signal "IN4")
		(26 "In12.Cu" signal "GND5")
		(28 "In13.Cu" signal "IN5")
		(30 "In14.Cu" signal "GND6")
		(32 "In15.Cu" signal "IN6")
		(34 "In16.Cu" signal "GND7")
		(2 "B.Cu" signal "BOTTOM")
		(9 "F.Adhes" user "F.Adhesive")
		(11 "B.Adhes" user "B.Adhesive")
		(13 "F.Paste" user "Package Geometry/Pastemask Top")
		(15 "B.Paste" user "Package Geometry/Pastemask Bottom")
		(5 "F.SilkS" user "Ref Des/Silkscreen Top")
		(7 "B.SilkS" user "Ref Des/Silkscreen Bottom")
		(1 "F.Mask" user "Board Geometry/Soldermask Top")
		(3 "B.Mask" user "Board Geometry/Soldermask Bottom")
		(17 "Dwgs.User" user "User.Drawings")
		(19 "Cmts.User" user "User.Comments")
		(21 "Eco1.User" user "User.Eco1")
		(23 "Eco2.User" user "User.Eco2")
		(25 "Edge.Cuts" user "Board Geometry/Outline")
		(27 "Margin" user)
		(31 "F.CrtYd" user "Package Geometry/Place Bound Top")
		(29 "B.CrtYd" user "Package Geometry/Place Bound Bottom")
		(35 "F.Fab" user "Ref Des/Assembly Top")
		(33 "B.Fab" user "Ref Des/Assembly Bottom")
	)
	(footprint ""
		(layer "F.Cu")
		(at 222.017336 -85.684868 180)
		(property "Reference" "R4266"
			(at 0 0 180)
			(layer "F.SilkS")
			(hide yes)
			(effects
				(font
					(size 1.27 1.27)
				)
			)
		)
		(property "Value" ""
			(at 0 0 180)
			(layer "F.Fab")
			(effects
				(font
					(size 1.27 1.27)
				)
			)
		)
		(duplicate_pad_numbers_are_jumpers no)
		(fp_line
			(start 0.7874 0.4064)
			(end -0.7874 0.4064)
			(stroke
				(width 0.1524)
				(type default)
			)
			(layer "F.SilkS")
		)
		(fp_line
			(start 0.7874 -0.4064)
			(end 0.7874 0.4064)
			(stroke
				(width 0.1524)
				(type default)
			)
			(layer "F.SilkS")
		)
		(fp_line
			(start -0.7874 0.4064)
			(end -0.7874 -0.4064)
			(stroke
				(width 0.1524)
				(type default)
			)
			(layer "F.SilkS")
		)
		(fp_line
			(start -0.7874 -0.4064)
			(end 0.7874 -0.4064)
			(stroke
				(width 0.1524)
				(type default)
			)
			(layer "F.SilkS")
		)
		(fp_line
			(start 0.67945 0.3048)
			(end 0.120396 0.3048)
			(stroke
				(width 0.1)
				(type default)
			)
			(layer "F.Fab")
		)
		(fp_line
			(start 0.67945 -0.3048)
			(end 0.67945 0.3048)
			(stroke
				(width 0.1)
				(type default)
			)
			(layer "F.Fab")
		)
		(fp_line
			(start 0.12065 -0.2794)
			(end 0.12065 -0.3048)
			(stroke
				(width 0.1)
				(type default)
			)
			(layer "F.Fab")
		)
		(fp_line
			(start 0.12065 -0.3048)
			(end 0.67945 -0.3048)
			(stroke
				(width 0.1)
				(type default)
			)
			(layer "F.Fab")
		)
		(fp_line
			(start 0.120396 0.3048)
			(end 0.120396 0.2794)
			(stroke
				(width 0.1)
				(type default)
			)
			(layer "F.Fab")
		)
		(fp_line
			(start 0.120396 0.2794)
			(end -0.12065 0.2794)
			(stroke
				(width 0.1)
				(type default)
			)
			(layer "F.Fab")
		)
		(fp_line
			(start -0.12065 0.3048)
			(end -0.67945 0.3048)
			(stroke
				(width 0.1)
				(type default)
			)
			(layer "F.Fab")
		)
		(fp_line
			(start -0.12065 0.2794)
			(end -0.12065 0.3048)
			(stroke
				(width 0.1)
				(type default)
			)
			(layer "F.Fab")
		)
		(fp_line
			(start -0.12065 -0.2794)
			(end 0.12065 -0.2794)
			(stroke
				(width 0.1)
				(type default)
			)
			(layer "F.Fab")
		)
		(fp_line
			(start -0.12065 -0.305054)
			(end -0.12065 -0.2794)
			(stroke
				(width 0.1)
				(type default)
			)
			(layer "F.Fab")
		)
		(fp_line
			(start -0.67945 0.3048)
			(end -0.67945 -0.305054)
			(stroke
				(width 0.1)
				(type default)
			)
			(layer "F.Fab")
		)
		(fp_line
			(start -0.67945 -0.305054)
			(end -0.12065 -0.305054)
			(stroke
				(width 0.1)
				(type default)
			)
			(layer "F.Fab")
		)
		(pad "1" smd circle
			(at -0.40005 0 180)
			(size 0 0)
			(layers "F.Cu" "F.Mask" "F.Paste")
			(net "SSD_LED_IOEXP_A0")
		)
		(pad "2" smd circle
			(at 0.40005 0 180)
			(size 0 0)
			(layers "F.Cu" "F.Mask" "F.Paste")
			(net "GND")
		)
	)
	(footprint ""
		(layer "F.Cu")
		(at 226.528376 -369.229386 90)
		(property "Reference" "PC13"
			(at 0 0 90)
			(layer "F.SilkS")
			(hide yes)
			(effects
				(font
					(size 1.27 1.27)
				)
			)
		)
		(property "Value" ""
			(at 0 0 90)
			(layer "F.Fab")
			(effects
				(font
					(size 1.27 1.27)
				)
			)
		)
		(duplicate_pad_numbers_are_jumpers no)
		(fp_line
			(start 0.7874 -0.4064)
			(end 0.7874 0.4064)
			(stroke
				(width 0.1524)
				(type default)
			)
			(layer "F.SilkS")
		)
		(fp_line
			(start -0.7874 -0.4064)
			(end 0.7874 -0.4064)
			(stroke
				(width 0.1524)
				(type default)
			)
			(layer "F.SilkS")
		)
		(fp_line
			(start 0.7874 0.4064)
			(end -0.7874 0.4064)
			(stroke
				(width 0.1524)
				(type default)
			)
			(layer "F.SilkS")
		)
		(fp_line
			(start -0.7874 0.4064)
			(end -0.7874 -0.4064)
			(stroke
				(width 0.1524)
				(type default)
			)
			(layer "F.SilkS")
		)
		(fp_line
			(start -0.12065 -0.305054)
			(end -0.12065 -0.2794)
			(stroke
				(width 0.1)
				(type default)
			)
			(layer "F.Fab")
		)
		(fp_line
			(start -0.67945 -0.305054)
			(end -0.12065 -0.305054)
			(stroke
				(width 0.1)
				(type default)
			)
			(layer "F.Fab")
		)
		(fp_line
			(start 0.67945 -0.3048)
			(end 0.67945 0.3048)
			(stroke
				(width 0.1)
				(type default)
			)
			(layer "F.Fab")
		)
		(fp_line
			(start 0.12065 -0.3048)
			(end 0.67945 -0.3048)
			(stroke
				(width 0.1)
				(type default)
			)
			(layer "F.Fab")
		)
		(fp_line
			(start 0.12065 -0.2794)
			(end 0.12065 -0.3048)
			(stroke
				(width 0.1)
				(type default)
			)
			(layer "F.Fab")
		)
		(fp_line
			(start -0.12065 -0.2794)
			(end 0.12065 -0.2794)
			(stroke
				(width 0.1)
				(type default)
			)
			(layer "F.Fab")
		)
		(fp_line
			(start 0.120396 0.2794)
			(end -0.12065 0.2794)
			(stroke
				(width 0.1)
				(type default)
			)
			(layer "F.Fab")
		)
		(fp_line
			(start -0.12065 0.2794)
			(end -0.12065 0.3048)
			(stroke
				(width 0.1)
				(type default)
			)
			(layer "F.Fab")
		)
		(fp_line
			(start 0.67945 0.3048)
			(end 0.120396 0.3048)
			(stroke
				(width 0.1)
				(type default)
			)
			(layer "F.Fab")
		)
		(fp_line
			(start 0.120396 0.3048)
			(end 0.120396 0.2794)
			(stroke
				(width 0.1)
				(type default)
			)
			(layer "F.Fab")
		)
		(fp_line
			(start -0.12065 0.3048)
			(end -0.67945 0.3048)
			(stroke
				(width 0.1)
				(type default)
			)
			(layer "F.Fab")
		)
		(fp_line
			(start -0.67945 0.3048)
			(end -0.67945 -0.305054)
			(stroke
				(width 0.1)
				(type default)
			)
			(layer "F.Fab")
		)
		(pad "1" smd circle
			(at -0.40005 0 90)
			(size 0 0)
			(layers "F.Cu" "F.Mask" "F.Paste")
			(net "HSC_VDD_2")
		)
		(pad "2" smd circle
			(at 0.40005 0 90)
			(size 0 0)
			(layers "F.Cu" "F.Mask" "F.Paste")
			(net "AGND_HSC")
		)
	)
	(footprint ""
		(layer "F.Cu")
		(at 352.232214 -143.51)
		(property "Reference" "R4840"
			(at 0 0 0)
			(layer "F.SilkS")
			(hide yes)
			(effects
				(font
					(size 1.27 1.27)
				)
			)
		)
		(property "Value" ""
			(at 0 0 0)
			(layer "F.Fab")
			(effects
				(font
					(size 1.27 1.27)
				)
			)
		)
		(duplicate_pad_numbers_are_jumpers no)
		(fp_line
			(start -0.7874 -0.4064)
			(end 0.7874 -0.4064)
			(stroke
				(width 0.1524)
				(type default)
			)
			(layer "F.SilkS")
		)
		(fp_line
			(start -0.7874 0.4064)
			(end -0.7874 -0.4064)
			(stroke
				(width 0.1524)
				(type default)
			)
			(layer "F.SilkS")
		)
		(fp_line
			(start 0.7874 -0.4064)
			(end 0.7874 0.4064)
			(stroke
				(width 0.1524)
				(type default)
			)
			(layer "F.SilkS")
		)
		(fp_line
			(start 0.7874 0.4064)
			(end -0.7874 0.4064)
			(stroke
				(width 0.1524)
				(type default)
			)
			(layer "F.SilkS")
		)
		(fp_line
			(start -0.67945 -0.305054)
			(end -0.12065 -0.305054)
			(stroke
				(width 0.1)
				(type default)
			)
			(layer "F.Fab")
		)
		(fp_line
			(start -0.67945 0.3048)
			(end -0.67945 -0.305054)
			(stroke
				(width 0.1)
				(type default)
			)
			(layer "F.Fab")
		)
		(fp_line
			(start -0.12065 -0.305054)
			(end -0.12065 -0.2794)
			(stroke
				(width 0.1)
				(type default)
			)
			(layer "F.Fab")
		)
		(fp_line
			(start -0.12065 -0.2794)
			(end 0.12065 -0.2794)
			(stroke
				(width 0.1)
				(type default)
			)
			(layer "F.Fab")
		)
		(fp_line
			(start -0.12065 0.2794)
			(end -0.12065 0.3048)
			(stroke
				(width 0.1)
				(type default)
			)
			(layer "F.Fab")
		)
		(fp_line
			(start -0.12065 0.3048)
			(end -0.67945 0.3048)
			(stroke
				(width 0.1)
				(type default)
			)
			(layer "F.Fab")
		)
		(fp_line
			(start 0.120396 0.2794)
			(end -0.12065 0.2794)
			(stroke
				(width 0.1)
				(type default)
			)
			(layer "F.Fab")
		)
		(fp_line
			(start 0.120396 0.3048)
			(end 0.120396 0.2794)
			(stroke
				(width 0.1)
				(type default)
			)
			(layer "F.Fab")
		)
		(fp_line
			(start 0.12065 -0.3048)
			(end 0.67945 -0.3048)
			(stroke
				(width 0.1)
				(type default)
			)
			(layer "F.Fab")
		)
		(fp_line
			(start 0.12065 -0.2794)
			(end 0.12065 -0.3048)
			(stroke
				(width 0.1)
				(type default)
			)
			(layer "F.Fab")
		)
		(fp_line
			(start 0.67945 -0.3048)
			(end 0.67945 0.3048)
			(stroke
				(width 0.1)
				(type default)
			)
			(layer "F.Fab")
		)
		(fp_line
			(start 0.67945 0.3048)
			(end 0.120396 0.3048)
			(stroke
				(width 0.1)
				(type default)
			)
			(layer "F.Fab")
		)
		(pad "1" smd circle
			(at -0.40005 0)
			(size 0 0)
			(layers "F.Cu" "F.Mask" "F.Paste")
			(net "NIC7_PEX_PWR_EN")
		)
		(pad "2" smd circle
			(at 0.40005 0)
			(size 0 0)
			(layers "F.Cu" "F.Mask" "F.Paste")
			(net "NIC7_PEX_PWR_EN_R")
		)
	)
	(footprint ""
		(layer "F.Cu")
		(at 321.414394 -311.227978 135)
		(property "Reference" "R1374"
			(at 0 0 135)
			(layer "F.SilkS")
			(hide yes)
			(effects
				(font
					(size 1.27 1.27)
				)
			)
		)
		(property "Value" ""
			(at 0 0 135)
			(layer "F.Fab")
			(effects
				(font
					(size 1.27 1.27)
				)
			)
		)
		(duplicate_pad_numbers_are_jumpers no)
		(fp_line
			(start 0.787389 -0.406267)
			(end 0.787389 0.406267)
			(stroke
				(width 0.1524)
				(type default)
			)
			(layer "F.SilkS")
		)
		(fp_line
			(start 0.787389 0.406267)
			(end -0.787389 0.406267)
			(stroke
				(width 0.1524)
				(type default)
			)
			(layer "F.SilkS")
		)
		(fp_line
			(start -0.787389 -0.406267)
			(end 0.787389 -0.406267)
			(stroke
				(width 0.1524)
				(type default)
			)
			(layer "F.SilkS")
		)
		(fp_line
			(start -0.787389 0.406267)
			(end -0.787389 -0.406267)
			(stroke
				(width 0.1524)
				(type default)
			)
			(layer "F.SilkS")
		)
		(fp_line
			(start 0.679446 -0.30479)
			(end 0.679446 0.30479)
			(stroke
				(width 0.1)
				(type default)
			)
			(layer "F.Fab")
		)
		(fp_line
			(start 0.120515 -0.30479)
			(end 0.679446 -0.30479)
			(stroke
				(width 0.1)
				(type default)
			)
			(layer "F.Fab")
		)
		(fp_line
			(start 0.120695 -0.279466)
			(end 0.120515 -0.30479)
			(stroke
				(width 0.1)
				(type default)
			)
			(layer "F.Fab")
		)
		(fp_line
			(start 0.679446 0.30479)
			(end 0.120515 0.30479)
			(stroke
				(width 0.1)
				(type default)
			)
			(layer "F.Fab")
		)
		(fp_line
			(start -0.120695 -0.304969)
			(end -0.120695 -0.279466)
			(stroke
				(width 0.1)
				(type default)
			)
			(layer "F.Fab")
		)
		(fp_line
			(start -0.120695 -0.279466)
			(end 0.120695 -0.279466)
			(stroke
				(width 0.1)
				(type default)
			)
			(layer "F.Fab")
		)
		(fp_line
			(start 0.120335 0.279466)
			(end -0.120695 0.279466)
			(stroke
				(width 0.1)
				(type default)
			)
			(layer "F.Fab")
		)
		(fp_line
			(start 0.120515 0.30479)
			(end 0.120335 0.279466)
			(stroke
				(width 0.1)
				(type default)
			)
			(layer "F.Fab")
		)
		(fp_line
			(start -0.679446 -0.305149)
			(end -0.120695 -0.304969)
			(stroke
				(width 0.1)
				(type default)
			)
			(layer "F.Fab")
		)
		(fp_line
			(start -0.120695 0.279466)
			(end -0.120515 0.30479)
			(stroke
				(width 0.1)
				(type default)
			)
			(layer "F.Fab")
		)
		(fp_line
			(start -0.120515 0.30479)
			(end -0.679446 0.30479)
			(stroke
				(width 0.1)
				(type default)
			)
			(layer "F.Fab")
		)
		(fp_line
			(start -0.679446 0.30479)
			(end -0.679446 -0.305149)
			(stroke
				(width 0.1)
				(type default)
			)
			(layer "F.Fab")
		)
		(pad "1" smd circle
			(at -0.40005 0 135)
			(size 0 0)
			(layers "F.Cu" "F.Mask" "F.Paste")
			(net "PEX2_SPARE0")
		)
		(pad "2" smd circle
			(at 0.40005 0 135)
			(size 0 0)
			(layers "F.Cu" "F.Mask" "F.Paste")
			(net "P1V8_PEX")
		)
	)
	(footprint ""
		(layer "F.Cu")
		(at 500.158512 -548.965882 180)
		(property "Reference" "HANDLE_1"
			(at -3.6322 -1.402334 0)
			(unlocked yes)
			(layer "B.SilkS")
			(effects
				(font
					(size 0.7874 0.5842)
					(thickness 0.1524)
				)
				(justify mirror)
			)
		)
		(property "Value" ""
			(at 0 0 180)
			(layer "F.Fab")
			(effects
				(font
					(size 1.27 1.27)
				)
			)
		)
		(duplicate_pad_numbers_are_jumpers no)
		(pad "1" thru_hole circle
			(at 0 0 180)
			(size 0.4572 0.4572)
			(drill 0.2032)
			(layers "*.Cu" "*.Mask")
			(remove_unused_layers no)
			(net "Net_9177")
			(clearance 0.127)
			(thermal_gap 0.127)
			(padstack
				(mode front_inner_back)
				(layer "Inner"
					(shape circle)
					(size 0.4572 0.4572)
					(clearance 0.127)
				)
				(layer "B.Cu"
					(shape circle)
					(size 0.508 0.508)
					(clearance 0.1016)
				)
			)
		)
	)
	(footprint ""
		(layer "F.Cu")
		(at 332.085442 -25.1587 -90)
		(property "Reference" "R5758"
			(at 0 0 270)
			(layer "F.SilkS")
			(hide yes)
			(effects
				(font
					(size 1.27 1.27)
				)
			)
		)
		(property "Value" ""
			(at 0 0 270)
			(layer "F.Fab")
			(effects
				(font
					(size 1.27 1.27)
				)
			)
		)
		(duplicate_pad_numbers_are_jumpers no)
		(fp_line
			(start -0.7874 0.4064)
			(end -0.7874 -0.4064)
			(stroke
				(width 0.1524)
				(type default)
			)
			(layer "F.SilkS")
		)
		(fp_line
			(start 0.7874 0.4064)
			(end -0.7874 0.4064)
			(stroke
				(width 0.1524)
				(type default)
			)
			(layer "F.SilkS")
		)
		(fp_line
			(start -0.7874 -0.4064)
			(end 0.7874 -0.4064)
			(stroke
				(width 0.1524)
				(type default)
			)
			(layer "F.SilkS")
		)
		(fp_line
			(start 0.7874 -0.4064)
			(end 0.7874 0.4064)
			(stroke
				(width 0.1524)
				(type default)
			)
			(layer "F.SilkS")
		)
		(fp_line
			(start -0.67945 0.3048)
			(end -0.67945 -0.305054)
			(stroke
				(width 0.1)
				(type default)
			)
			(layer "F.Fab")
		)
		(fp_line
			(start -0.12065 0.3048)
			(end -0.67945 0.3048)
			(stroke
				(width 0.1)
				(type default)
			)
			(layer "F.Fab")
		)
		(fp_line
			(start 0.120396 0.3048)
			(end 0.120396 0.2794)
			(stroke
				(width 0.1)
				(type default)
			)
			(layer "F.Fab")
		)
		(fp_line
			(start 0.67945 0.3048)
			(end 0.120396 0.3048)
			(stroke
				(width 0.1)
				(type default)
			)
			(layer "F.Fab")
		)
		(fp_line
			(start -0.12065 0.2794)
			(end -0.12065 0.3048)
			(stroke
				(width 0.1)
				(type default)
			)
			(layer "F.Fab")
		)
		(fp_line
			(start 0.120396 0.2794)
			(end -0.12065 0.2794)
			(stroke
				(width 0.1)
				(type default)
			)
			(layer "F.Fab")
		)
		(fp_line
			(start -0.12065 -0.2794)
			(end 0.12065 -0.2794)
			(stroke
				(width 0.1)
				(type default)
			)
			(layer "F.Fab")
		)
		(fp_line
			(start 0.12065 -0.2794)
			(end 0.12065 -0.3048)
			(stroke
				(width 0.1)
				(type default)
			)
			(layer "F.Fab")
		)
		(fp_line
			(start 0.12065 -0.3048)
			(end 0.67945 -0.3048)
			(stroke
				(width 0.1)
				(type default)
			)
			(layer "F.Fab")
		)
		(fp_line
			(start 0.67945 -0.3048)
			(end 0.67945 0.3048)
			(stroke
				(width 0.1)
				(type default)
			)
			(layer "F.Fab")
		)
		(fp_line
			(start -0.67945 -0.305054)
			(end -0.12065 -0.305054)
			(stroke
				(width 0.1)
				(type default)
			)
			(layer "F.Fab")
		)
		(fp_line
			(start -0.12065 -0.305054)
			(end -0.12065 -0.2794)
			(stroke
				(width 0.1)
				(type default)
			)
			(layer "F.Fab")
		)
		(pad "1" smd circle
			(at -0.40005 0 270)
			(size 0 0)
			(layers "F.Cu" "F.Mask" "F.Paste")
			(net "SSD11_LED_ISO_N")
		)
		(pad "2" smd circle
			(at 0.40005 0 270)
			(size 0 0)
			(layers "F.Cu" "F.Mask" "F.Paste")
			(net "SSD11_LED_ISO_R_N")
		)
	)
	(footprint ""
		(layer "F.Cu")
		(at 196.359272 -343.952322 90)
		(property "Reference" "C2542"
			(at 0 0 90)
			(layer "F.SilkS")
			(hide yes)
			(effects
				(font
					(size 1.27 1.27)
				)
			)
		)
		(property "Value" ""
			(at 0 0 90)
			(layer "F.Fab")
			(effects
				(font
					(size 1.27 1.27)
				)
			)
		)
		(duplicate_pad_numbers_are_jumpers no)
		(fp_line
			(start 0.299974 -0.150114)
			(end 0.299974 0.150114)
			(stroke
				(width 0.1)
				(type default)
			)
			(layer "F.Fab")
		)
		(fp_line
			(start -0.299974 -0.150114)
			(end 0.299974 -0.150114)
			(stroke
				(width 0.1)
				(type default)
			)
			(layer "F.Fab")
		)
		(fp_line
			(start 0.299974 0.150114)
			(end -0.299974 0.150114)
			(stroke
				(width 0.1)
				(type default)
			)
			(layer "F.Fab")
		)
		(fp_line
			(start -0.299974 0.150114)
			(end -0.299974 -0.150114)
			(stroke
				(width 0.1)
				(type default)
			)
			(layer "F.Fab")
		)
		(pad "1" smd rect
			(at -0.2667 0 90)
			(size 0.3048 0.381)
			(layers "F.Cu" "F.Mask" "F.Paste")
			(net "P5E_PEX1_STN4_TX_DP<64>")
		)
		(pad "2" smd rect
			(at 0.2667 0 90)
			(size 0.3048 0.381)
			(layers "F.Cu" "F.Mask" "F.Paste")
			(net "P5E_PEX1_STN4_TX_C_DP<64>")
		)
	)
)
